FILE_TYPE = CONNECTIVITY;
{Allegro Design Entry HDL 16.6-p007 (v16-6-112F) 10/10/2012}
"PAGE_NUMBER" = 80;
0"NC";
1"M_H_DQS_DP<17:0>";
2"M_H_DQS_DN<17:0>";
3"M_H_DQ<63:0>";
4"M_H_MA<17:0>";
5"M_H_CLK_DN<3:0>";
6"M_H_CLK_DP<3:0>";
7"M_H_BA<1:0>";
8"M_H_BG<1:0>";
9"M_H_CS_N<7:0>";
10"M_H_CKE<3:0>";
11"M_H_ODT<3:0>";
12"M_H_ECC<7:0>";
13"GND\g";
14"GND\g";
15"GND\g";
16"P12V_NVDIMM_GHJ\g";
17"GND\g";
18"PVDDQ_GHJ\g";
19"PVTT_GHJ\g";
20"PVPP_GHJ\g";
21"PVPP_GHJ\g";
22"M_H_DQS_DP<7>";
23"M_H_DQS_DP<6>";
24"M_H_DQ<57>";
25"M_H_DQS_DP<10>";
26"M_H_DQS_DN<10>";
27"M_H_DQ<63>";
28"M_H_DQ<46>";
29"M_H_DQS_DN<4>";
30"M_H_DQS_DP<3>";
31"M_H_DQS_DN<3>";
32"M_H_DQ<59>";
33"M_H_DQ<53>";
34"M_H_DQ<52>";
35"FM_DIMM_EVENT_COD_N";
36"M_H_VREF";
37"TP_CH_H_DIMM0_RFU_2";
38"TP_CH_H_DIMM0_RFU_0";
39"TP_CH_H_DIMM0_RFU_1";
40"M_H_ACT_N";
41"FM_ADR_COMPLETE_GHJ_N";
42"SMB_DDR_GHJ_VPP_SCL";
43"SMB_DDR_GHJ_VPP_SDA";
44"M_H_ALERT_N";
45"M_H_ECC<1>";
46"M_H_ECC<0>";
47"M_H_DQ<16>";
48"M_H_DQ<13>";
49"M_H_DQ<11>";
50"M_H_DQ<10>";
51"M_H_DQ<8>";
52"M_H_DQ<6>";
53"M_H_DQ<1>";
54"M_H_DQ<0>";
55"M_H_DQ<15>";
56"M_H_DQ<4>";
57"M_H_DQ<2>";
58"M_H_DQ<3>";
59"M_H_DQ<7>";
60"M_H_DQ<9>";
61"M_H_DQ<14>";
62"M_H_DQ<5>";
63"M_H_DQ<12>";
64"M_H_PAR";
65"M_GHJ_RST_N";
66"M_H_ECC<6>";
67"M_H_ECC<5>";
68"M_H_ECC<4>";
69"M_H_ECC<3>";
70"M_H_ECC<2>";
71"M_H_ECC<7>";
72"M_H_ODT<2>";
73"M_H_ODT<3>";
74"M_H_CKE<2>";
75"M_H_C<2>";
76"M_H_CLK_DP<2>";
77"M_H_CS_N<7>";
78"M_H_CS_N<6>";
79"M_H_CS_N<5>";
80"M_H_CKE<3>";
81"M_H_CS_N<4>";
82"M_H_CLK_DN<2>";
83"M_H_BA<1>";
84"M_H_MA<0>";
85"M_H_MA<1>";
86"M_H_BG<0>";
87"M_H_BG<1>";
88"M_H_BA<0>";
89"M_H_CLK_DP<3>";
90"M_H_CLK_DN<3>";
91"M_H_MA<3>";
92"M_H_MA<4>";
93"M_H_MA<5>";
94"M_H_MA<6>";
95"M_H_MA<7>";
96"M_H_MA<8>";
97"M_H_MA<9>";
98"M_H_MA<2>";
99"M_H_MA<10>";
100"M_H_MA<11>";
101"M_H_DQ<29>";
102"M_H_DQ<28>";
103"M_H_DQ<37>";
104"M_H_DQ<34>";
105"M_H_DQ<33>";
106"M_H_DQ<32>";
107"M_H_DQ<31>";
108"M_H_DQ<30>";
109"M_H_DQ<24>";
110"M_H_DQ<22>";
111"M_H_DQ<21>";
112"M_H_DQ<20>";
113"M_H_DQ<18>";
114"M_H_DQ<35>";
115"M_H_DQ<36>";
116"M_H_DQ<27>";
117"M_H_DQ<17>";
118"M_H_DQ<23>";
119"M_H_DQ<25>";
120"M_H_DQ<26>";
121"M_H_DQ<19>";
122"M_H_DQ<56>";
123"M_H_DQ<55>";
124"M_H_DQ<45>";
125"M_H_DQ<44>";
126"M_H_DQ<43>";
127"M_H_DQ<42>";
128"M_H_DQ<41>";
129"M_H_DQ<40>";
130"M_H_DQ<39>";
131"M_H_DQ<38>";
132"M_H_DQ<54>";
133"M_H_DQ<51>";
134"M_H_DQ<49>";
135"M_H_DQ<48>";
136"M_H_DQ<47>";
137"M_H_DQ<50>";
138"M_H_MA<12>";
139"M_H_MA<13>";
140"M_H_MA<17>";
141"M_H_MA<14>";
142"M_H_MA<15>";
143"M_H_MA<16>";
144"M_H_DQ<61>";
145"M_H_DQ<60>";
146"M_H_DQ<58>";
147"M_H_DQ<62>";
148"M_H_DQS_DN<0>";
149"M_H_DQS_DP<0>";
150"M_H_DQS_DN<11>";
151"M_H_DQS_DP<11>";
152"M_H_DQS_DN<12>";
153"M_H_DQS_DN<1>";
154"M_H_DQS_DP<1>";
155"M_H_DQS_DN<2>";
156"M_H_DQS_DP<2>";
157"M_H_DQS_DP<4>";
158"M_H_DQS_DN<5>";
159"M_H_DQS_DP<5>";
160"M_H_DQS_DN<6>";
161"M_H_DQS_DN<7>";
162"M_H_DQS_DN<8>";
163"M_H_DQS_DP<8>";
164"M_H_DQS_DN<9>";
165"M_H_DQS_DP<9>";
166"M_H_DQS_DP<12>";
167"M_H_DQS_DN<13>";
168"M_H_DQS_DP<13>";
169"M_H_DQS_DN<14>";
170"M_H_DQS_DP<14>";
171"M_H_DQS_DN<15>";
172"M_H_DQS_DP<15>";
173"M_H_DQS_DN<16>";
174"M_H_DQS_DP<16>";
175"M_H_DQS_DN<17>";
176"M_H_DQS_DP<17>";
%"GND"
"1","(-7825,1350)","2","mstr_symbols","I1";
;
VOLTAGE"0"
CDS_LIB"mstr_symbols"
SIZE"1B"
BOM_COST"MEM"
BODY_TYPE"PLUMBING"
ROOM"DDR4_GH_G"
HDL_POWER"GND";
"A\NAC"13;
%"TAP"
"6","(-4475,3450)","2","mstr_standard","I100";
;
CDS_LIB"mstr_standard"
BODY_TYPE"PLUMBING"
HDL_TAP"TRUE";
"B \NAC \NWC"3;
"S \NAC"
BN"45"124;
%"SCONN288_H44441003"
"2","(-2675,3750)","0","mstr_sconn","I101";
;
CDS_SEC"2"
LOCATION"J9U1"
PART_NUMBER"H44441-003"
MATERIAL"SCONN"
BOM_SS"NOPOP"
PACK_TYPE"PIP"
BOM_COST"MEM"
CDS_LIB"mstr_sconn"
SEC_TYPE"PIP"
SEC"2"
CDS_LOCATION"J9U1"
ROOM"DDR4_GH_H";
"DQS0N"
$PN"152"148;
"DQS0P"
$PN"153"149;
"DQS10N"
$PN"19"26;
"DQS10P"
$PN"18"25;
"DQS11N"
$PN"30"150;
"DQS11P"
$PN"29"151;
"DQS12N"
$PN"41"152;
"DQS12P"
$PN"40"166;
"DQS13N"
$PN"100"167;
"DQS13P"
$PN"99"168;
"DQS14N"
$PN"111"169;
"DQS14P"
$PN"110"170;
"DQS15N"
$PN"122"171;
"DQS15P"
$PN"121"172;
"DQS16N"
$PN"133"173;
"DQS16P"
$PN"132"174;
"DQS17N"
$PN"52"175;
"DQS17P"
$PN"51"176;
"DQS1N"
$PN"163"153;
"DQS1P"
$PN"164"154;
"DQS2N"
$PN"174"155;
"DQS2P"
$PN"175"156;
"DQS3N"
$PN"185"31;
"DQS3P"
$PN"186"30;
"DQS4N"
$PN"244"29;
"DQS4P"
$PN"245"157;
"DQS5N"
$PN"255"158;
"DQS5P"
$PN"256"159;
"DQS6N"
$PN"266"160;
"DQS6P"
$PN"267"23;
"DQS7N"
$PN"277"161;
"DQS7P"
$PN"278"22;
"DQS8N"
$PN"196"162;
"DQS8P"
$PN"197"163;
"DQS9N"
$PN"8"164;
"DQS9P"
$PN"7"165;
%"TAP"
"6","(-5975,3550)","0","mstr_standard","I102";
;
CDS_LIB"mstr_standard"
BODY_TYPE"PLUMBING"
HDL_TAP"TRUE";
"B \NAC \NWC"4;
"S \NAC"
BN"1"85;
%"TAP"
"6","(-5975,3600)","0","mstr_standard","I103";
;
CDS_LIB"mstr_standard"
BODY_TYPE"PLUMBING"
HDL_TAP"TRUE";
"B \NAC \NWC"4;
"S \NAC"
BN"2"98;
%"TAP"
"6","(-5975,3650)","0","mstr_standard","I104";
;
CDS_LIB"mstr_standard"
BODY_TYPE"PLUMBING"
HDL_TAP"TRUE";
"B \NAC \NWC"4;
"S \NAC"
BN"3"91;
%"TAP"
"6","(-5975,3750)","0","mstr_standard","I105";
;
CDS_LIB"mstr_standard"
BODY_TYPE"PLUMBING"
HDL_TAP"TRUE";
"B \NAC \NWC"4;
"S \NAC"
BN"5"93;
%"TAP"
"6","(-5975,3700)","0","mstr_standard","I106";
;
CDS_LIB"mstr_standard"
BODY_TYPE"PLUMBING"
HDL_TAP"TRUE";
"B \NAC \NWC"4;
"S \NAC"
BN"4"92;
%"TAP"
"6","(-5975,3800)","0","mstr_standard","I107";
;
CDS_LIB"mstr_standard"
BODY_TYPE"PLUMBING"
HDL_TAP"TRUE";
"B \NAC \NWC"4;
"S \NAC"
BN"6"94;
%"TAP"
"6","(-5975,3900)","0","mstr_standard","I108";
;
CDS_LIB"mstr_standard"
BODY_TYPE"PLUMBING"
HDL_TAP"TRUE";
"B \NAC \NWC"4;
"S \NAC"
BN"8"96;
%"TAP"
"6","(-5975,3850)","0","mstr_standard","I109";
;
CDS_LIB"mstr_standard"
BODY_TYPE"PLUMBING"
HDL_TAP"TRUE";
"B \NAC \NWC"4;
"S \NAC"
BN"7"95;
%"TAP"
"6","(-5975,4000)","0","mstr_standard","I110";
;
CDS_LIB"mstr_standard"
BODY_TYPE"PLUMBING"
HDL_TAP"TRUE";
"B \NAC \NWC"4;
"S \NAC"
BN"10"99;
%"TAP"
"6","(-5975,3950)","0","mstr_standard","I111";
;
CDS_LIB"mstr_standard"
BODY_TYPE"PLUMBING"
HDL_TAP"TRUE";
"B \NAC \NWC"4;
"S \NAC"
BN"9"97;
%"TAP"
"6","(-5975,4050)","0","mstr_standard","I112";
;
CDS_LIB"mstr_standard"
BODY_TYPE"PLUMBING"
HDL_TAP"TRUE";
"B \NAC \NWC"4;
"S \NAC"
BN"11"100;
%"TAP"
"6","(-5975,4100)","0","mstr_standard","I113";
;
CDS_LIB"mstr_standard"
BODY_TYPE"PLUMBING"
HDL_TAP"TRUE";
"B \NAC \NWC"4;
"S \NAC"
BN"12"138;
%"TAP"
"6","(-5975,4150)","0","mstr_standard","I114";
;
CDS_LIB"mstr_standard"
BODY_TYPE"PLUMBING"
HDL_TAP"TRUE";
"B \NAC \NWC"4;
"S \NAC"
BN"13"139;
%"TAP"
"6","(-5975,4250)","0","mstr_standard","I115";
;
CDS_LIB"mstr_standard"
BODY_TYPE"PLUMBING"
HDL_TAP"TRUE";
"B \NAC \NWC"4;
"S \NAC"
BN"15"142;
%"TAP"
"6","(-5975,4200)","0","mstr_standard","I116";
;
CDS_LIB"mstr_standard"
BODY_TYPE"PLUMBING"
HDL_TAP"TRUE";
"B \NAC \NWC"4;
"S \NAC"
BN"14"141;
%"TAP"
"6","(-5975,4300)","0","mstr_standard","I117";
;
CDS_LIB"mstr_standard"
BODY_TYPE"PLUMBING"
HDL_TAP"TRUE";
"B \NAC \NWC"4;
"S \NAC"
BN"16"143;
%"TAP"
"6","(-5975,4350)","0","mstr_standard","I118";
;
CDS_LIB"mstr_standard"
BODY_TYPE"PLUMBING"
HDL_TAP"TRUE";
"B \NAC \NWC"4;
"S \NAC"
BN"17"140;
%"TAP"
"6","(-4475,3550)","2","mstr_standard","I119";
;
CDS_LIB"mstr_standard"
BODY_TYPE"PLUMBING"
HDL_TAP"TRUE";
"B \NAC \NWC"3;
"S \NAC"
BN"47"136;
%"TAP"
"6","(-4475,3600)","2","mstr_standard","I120";
;
CDS_LIB"mstr_standard"
BODY_TYPE"PLUMBING"
HDL_TAP"TRUE";
"B \NAC \NWC"3;
"S \NAC"
BN"48"135;
%"TAP"
"6","(-4475,3650)","2","mstr_standard","I121";
;
CDS_LIB"mstr_standard"
BODY_TYPE"PLUMBING"
HDL_TAP"TRUE";
"B \NAC \NWC"3;
"S \NAC"
BN"49"134;
%"TAP"
"6","(-4475,3800)","2","mstr_standard","I122";
;
CDS_LIB"mstr_standard"
BODY_TYPE"PLUMBING"
HDL_TAP"TRUE";
"B \NAC \NWC"3;
"S \NAC"
BN"52"34;
%"TAP"
"6","(-4475,3700)","2","mstr_standard","I123";
;
CDS_LIB"mstr_standard"
BODY_TYPE"PLUMBING"
HDL_TAP"TRUE";
"B \NAC \NWC"3;
"S \NAC"
BN"50"137;
%"TAP"
"6","(-4475,3750)","2","mstr_standard","I124";
;
CDS_LIB"mstr_standard"
BODY_TYPE"PLUMBING"
HDL_TAP"TRUE";
"B \NAC \NWC"3;
"S \NAC"
BN"51"133;
%"TAP"
"6","(-4475,3850)","2","mstr_standard","I125";
;
CDS_LIB"mstr_standard"
BODY_TYPE"PLUMBING"
HDL_TAP"TRUE";
"B \NAC \NWC"3;
"S \NAC"
BN"53"33;
%"TAP"
"6","(-4475,3900)","2","mstr_standard","I126";
;
CDS_LIB"mstr_standard"
BODY_TYPE"PLUMBING"
HDL_TAP"TRUE";
"B \NAC \NWC"3;
"S \NAC"
BN"54"132;
%"TAP"
"6","(-4475,4050)","2","mstr_standard","I127";
;
CDS_LIB"mstr_standard"
BODY_TYPE"PLUMBING"
HDL_TAP"TRUE";
"B \NAC \NWC"3;
"S \NAC"
BN"57"24;
%"TAP"
"6","(-4475,3950)","2","mstr_standard","I128";
;
CDS_LIB"mstr_standard"
BODY_TYPE"PLUMBING"
HDL_TAP"TRUE";
"B \NAC \NWC"3;
"S \NAC"
BN"55"123;
%"TAP"
"6","(-4475,4000)","2","mstr_standard","I129";
;
CDS_LIB"mstr_standard"
BODY_TYPE"PLUMBING"
HDL_TAP"TRUE";
"B \NAC \NWC"3;
"S \NAC"
BN"56"122;
%"TAP"
"6","(-4475,4150)","2","mstr_standard","I130";
;
CDS_LIB"mstr_standard"
BODY_TYPE"PLUMBING"
HDL_TAP"TRUE";
"B \NAC \NWC"3;
"S \NAC"
BN"59"32;
%"TAP"
"6","(-4475,4100)","2","mstr_standard","I131";
;
CDS_LIB"mstr_standard"
BODY_TYPE"PLUMBING"
HDL_TAP"TRUE";
"B \NAC \NWC"3;
"S \NAC"
BN"58"146;
%"TAP"
"6","(-4475,4300)","2","mstr_standard","I132";
;
CDS_LIB"mstr_standard"
BODY_TYPE"PLUMBING"
HDL_TAP"TRUE";
"B \NAC \NWC"3;
"S \NAC"
BN"62"147;
%"TAP"
"6","(-4475,4200)","2","mstr_standard","I133";
;
CDS_LIB"mstr_standard"
BODY_TYPE"PLUMBING"
HDL_TAP"TRUE";
"B \NAC \NWC"3;
"S \NAC"
BN"60"145;
%"TAP"
"6","(-4475,4250)","2","mstr_standard","I134";
;
CDS_LIB"mstr_standard"
BODY_TYPE"PLUMBING"
HDL_TAP"TRUE";
"B \NAC \NWC"3;
"S \NAC"
BN"61"144;
%"TAP"
"6","(-4475,4350)","2","mstr_standard","I135";
;
CDS_LIB"mstr_standard"
BODY_TYPE"PLUMBING"
HDL_TAP"TRUE";
"B \NAC \NWC"3;
"S \NAC"
BN"63"27;
%"GND"
"1","(-1575,550)","2","mstr_symbols","I137";
;
VOLTAGE"0"
CDS_LIB"mstr_symbols"
SIZE"1B"
BOM_COST"MEM"
BODY_TYPE"PLUMBING"
ROOM"DDR4_GH_G"
HDL_POWER"GND";
"A\NAC"14;
%"SCONN288_H44441003"
"3","(-875,1850)","0","mstr_sconn","I138";
;
CDS_SEC"3"
LOCATION"J9U1"
PART_NUMBER"H44441-003"
MATERIAL"SCONN"
BOM_SS"NOPOP"
PACK_TYPE"PIP"
BOM_COST"MEM"
CDS_LIB"mstr_sconn"
SEC_TYPE"PIP"
SEC"3"
CDS_LOCATION"J9U1"
ROOM"DDR4_GH_H";
"VSS<46>"
$PN"147"15;
"VSS<45>"
$PN"149"15;
"VSS<87>"
$PN"15"14;
"VSS<86>"
$PN"17"14;
"VSS<85>"
$PN"20"14;
"VSS<84>"
$PN"22"14;
"VSS<83>"
$PN"24"14;
"VSS<82>"
$PN"26"14;
"VSS<81>"
$PN"28"14;
"VSS<80>"
$PN"31"14;
"VSS<79>"
$PN"33"14;
"VSS<78>"
$PN"35"14;
"VSS<77>"
$PN"37"14;
"VSS<76>"
$PN"39"14;
"VSS<75>"
$PN"42"14;
"VSS<74>"
$PN"44"14;
"VSS<73>"
$PN"46"14;
"VSS<72>"
$PN"48"14;
"VSS<71>"
$PN"50"14;
"VSS<70>"
$PN"53"14;
"VSS<69>"
$PN"55"14;
"VSS<68>"
$PN"57"14;
"VSS<67>"
$PN"94"14;
"VSS<66>"
$PN"96"14;
"VSS<65>"
$PN"98"14;
"VSS<64>"
$PN"101"14;
"VSS<63>"
$PN"103"14;
"VSS<62>"
$PN"105"14;
"VSS<61>"
$PN"107"14;
"VSS<60>"
$PN"109"14;
"VSS<59>"
$PN"112"14;
"VSS<58>"
$PN"114"14;
"VSS<57>"
$PN"116"14;
"VSS<56>"
$PN"118"14;
"VSS<55>"
$PN"120"14;
"VSS<54>"
$PN"123"14;
"VSS<53>"
$PN"125"14;
"VSS<52>"
$PN"127"14;
"VSS<51>"
$PN"129"14;
"VSS<50>"
$PN"131"14;
"VSS<49>"
$PN"134"14;
"VSS<48>"
$PN"136"14;
"VSS<47>"
$PN"138"14;
"VSS<44>"
$PN"151"15;
"VSS<43>"
$PN"154"15;
"VSS<42>"
$PN"156"15;
"VSS<41>"
$PN"158"15;
"VSS<40>"
$PN"160"15;
"VSS<39>"
$PN"162"15;
"VSS<38>"
$PN"165"15;
"VSS<37>"
$PN"167"15;
"VSS<36>"
$PN"169"15;
"VSS<35>"
$PN"171"15;
"VSS<34>"
$PN"173"15;
"VSS<33>"
$PN"176"15;
"VSS<32>"
$PN"178"15;
"VSS<31>"
$PN"180"15;
"VSS<30>"
$PN"182"15;
"VSS<29>"
$PN"184"15;
"VSS<28>"
$PN"187"15;
"VSS<27>"
$PN"189"15;
"VSS<26>"
$PN"191"15;
"VSS<25>"
$PN"193"15;
"VSS<24>"
$PN"195"15;
"VSS<23>"
$PN"198"15;
"VSS<22>"
$PN"200"15;
"VSS<21>"
$PN"202"15;
"VSS<20>"
$PN"239"15;
"VSS<19>"
$PN"241"15;
"VSS<18>"
$PN"243"15;
"VSS<17>"
$PN"246"15;
"VSS<16>"
$PN"248"15;
"VSS<15>"
$PN"250"15;
"VSS<14>"
$PN"252"15;
"VSS<13>"
$PN"254"15;
"VSS<12>"
$PN"257"15;
"VSS<11>"
$PN"259"15;
"VSS<10>"
$PN"261"15;
"VSS<9>"
$PN"263"15;
"VSS<8>"
$PN"265"15;
"VSS<7>"
$PN"268"15;
"VSS<6>"
$PN"270"15;
"VSS<5>"
$PN"272"15;
"VSS<4>"
$PN"274"15;
"VSS<3>"
$PN"276"15;
"VSS<2>"
$PN"279"15;
"VSS<1>"
$PN"281"15;
"VSS<0>"
$PN"283"15;
"VSS<88>"
$PN"13"14;
"VSS<89>"
$PN"11"14;
"VSS<90>"
$PN"9"14;
"VSS<91>"
$PN"6"14;
"VSS<92>"
$PN"4"14;
"VSS<93>"
$PN"2"14;
%"TAP"
"6","(-1975,3000)","2","mstr_standard","I142";
;
CDS_LIB"mstr_standard"
BODY_TYPE"PLUMBING"
HDL_TAP"TRUE";
"B \NAC \NWC"1;
"S \NAC"
BN"1"154;
%"TAP"
"6","(-1975,2900)","2","mstr_standard","I143";
;
CDS_LIB"mstr_standard"
BODY_TYPE"PLUMBING"
HDL_TAP"TRUE";
"B \NAC \NWC"1;
"S \NAC"
BN"0"149;
%"TAP"
"6","(-1775,2850)","2","mstr_standard","I144";
;
CDS_LIB"mstr_standard"
BODY_TYPE"PLUMBING"
HDL_TAP"TRUE";
"B \NAC \NWC"2;
"S \NAC"
BN"0"148;
%"TAP"
"6","(-1775,2950)","2","mstr_standard","I145";
;
CDS_LIB"mstr_standard"
BODY_TYPE"PLUMBING"
HDL_TAP"TRUE";
"B \NAC \NWC"2;
"S \NAC"
BN"1"153;
%"TAP"
"6","(-1975,3100)","2","mstr_standard","I146";
;
CDS_LIB"mstr_standard"
BODY_TYPE"PLUMBING"
HDL_TAP"TRUE";
"B \NAC \NWC"1;
"S \NAC"
BN"2"156;
%"TAP"
"6","(-1975,3200)","2","mstr_standard","I147";
;
CDS_LIB"mstr_standard"
BODY_TYPE"PLUMBING"
HDL_TAP"TRUE";
"B \NAC \NWC"1;
"S \NAC"
BN"3"30;
%"TAP"
"6","(-1975,3500)","2","mstr_standard","I148";
;
CDS_LIB"mstr_standard"
BODY_TYPE"PLUMBING"
HDL_TAP"TRUE";
"B \NAC \NWC"1;
"S \NAC"
BN"6"23;
%"TAP"
"6","(-1975,3400)","2","mstr_standard","I149";
;
CDS_LIB"mstr_standard"
BODY_TYPE"PLUMBING"
HDL_TAP"TRUE";
"B \NAC \NWC"1;
"S \NAC"
BN"5"159;
%"TAP"
"6","(-1975,3300)","2","mstr_standard","I150";
;
CDS_LIB"mstr_standard"
BODY_TYPE"PLUMBING"
HDL_TAP"TRUE";
"B \NAC \NWC"1;
"S \NAC"
BN"4"157;
%"TAP"
"6","(-1775,3150)","2","mstr_standard","I151";
;
CDS_LIB"mstr_standard"
BODY_TYPE"PLUMBING"
HDL_TAP"TRUE";
"B \NAC \NWC"2;
"S \NAC"
BN"3"31;
%"TAP"
"6","(-1775,3050)","2","mstr_standard","I152";
;
CDS_LIB"mstr_standard"
BODY_TYPE"PLUMBING"
HDL_TAP"TRUE";
"B \NAC \NWC"2;
"S \NAC"
BN"2"155;
%"TAP"
"6","(-1775,3250)","2","mstr_standard","I153";
;
CDS_LIB"mstr_standard"
BODY_TYPE"PLUMBING"
HDL_TAP"TRUE";
"B \NAC \NWC"2;
"S \NAC"
BN"4"29;
%"TAP"
"6","(-1775,3350)","2","mstr_standard","I154";
;
CDS_LIB"mstr_standard"
BODY_TYPE"PLUMBING"
HDL_TAP"TRUE";
"B \NAC \NWC"2;
"S \NAC"
BN"5"158;
%"TAP"
"6","(-1775,3450)","2","mstr_standard","I155";
;
CDS_LIB"mstr_standard"
BODY_TYPE"PLUMBING"
HDL_TAP"TRUE";
"B \NAC \NWC"2;
"S \NAC"
BN"6"160;
%"GND"
"1","(-175,550)","2","mstr_symbols","I156";
;
VOLTAGE"0"
CDS_LIB"mstr_symbols"
SIZE"1B"
BOM_COST"MEM"
BODY_TYPE"PLUMBING"
ROOM"DDR4_GH_G"
HDL_POWER"GND";
"A\NAC"15;
%"TAP"
"6","(-1975,3800)","2","mstr_standard","I157";
;
CDS_LIB"mstr_standard"
BODY_TYPE"PLUMBING"
HDL_TAP"TRUE";
"B \NAC \NWC"1;
"S \NAC"
BN"9"165;
%"TAP"
"6","(-1975,3600)","2","mstr_standard","I158";
;
CDS_LIB"mstr_standard"
BODY_TYPE"PLUMBING"
HDL_TAP"TRUE";
"B \NAC \NWC"1;
"S \NAC"
BN"7"22;
%"TAP"
"6","(-1975,3700)","2","mstr_standard","I159";
;
CDS_LIB"mstr_standard"
BODY_TYPE"PLUMBING"
HDL_TAP"TRUE";
"B \NAC \NWC"1;
"S \NAC"
BN"8"163;
%"TAP"
"6","(-1975,4000)","2","mstr_standard","I160";
;
CDS_LIB"mstr_standard"
BODY_TYPE"PLUMBING"
HDL_TAP"TRUE";
"B \NAC \NWC"1;
"S \NAC"
BN"11"151;
%"TAP"
"6","(-1975,3900)","2","mstr_standard","I161";
;
CDS_LIB"mstr_standard"
BODY_TYPE"PLUMBING"
HDL_TAP"TRUE";
"B \NAC \NWC"1;
"S \NAC"
BN"10"25;
%"TAP"
"6","(-1775,3650)","2","mstr_standard","I162";
;
CDS_LIB"mstr_standard"
BODY_TYPE"PLUMBING"
HDL_TAP"TRUE";
"B \NAC \NWC"2;
"S \NAC"
BN"8"162;
%"TAP"
"6","(-1775,3550)","2","mstr_standard","I163";
;
CDS_LIB"mstr_standard"
BODY_TYPE"PLUMBING"
HDL_TAP"TRUE";
"B \NAC \NWC"2;
"S \NAC"
BN"7"161;
%"TAP"
"6","(-1775,3750)","2","mstr_standard","I164";
;
CDS_LIB"mstr_standard"
BODY_TYPE"PLUMBING"
HDL_TAP"TRUE";
"B \NAC \NWC"2;
"S \NAC"
BN"9"164;
%"TAP"
"6","(-1775,3850)","2","mstr_standard","I165";
;
CDS_LIB"mstr_standard"
BODY_TYPE"PLUMBING"
HDL_TAP"TRUE";
"B \NAC \NWC"2;
"S \NAC"
BN"10"26;
%"TAP"
"6","(-1775,3950)","2","mstr_standard","I166";
;
CDS_LIB"mstr_standard"
BODY_TYPE"PLUMBING"
HDL_TAP"TRUE";
"B \NAC \NWC"2;
"S \NAC"
BN"11"150;
%"TAP"
"6","(-1775,4050)","2","mstr_standard","I167";
;
CDS_LIB"mstr_standard"
BODY_TYPE"PLUMBING"
HDL_TAP"TRUE";
"B \NAC \NWC"2;
"S \NAC"
BN"12"152;
%"TAP"
"6","(-1975,4300)","2","mstr_standard","I168";
;
CDS_LIB"mstr_standard"
BODY_TYPE"PLUMBING"
HDL_TAP"TRUE";
"B \NAC \NWC"1;
"S \NAC"
BN"14"170;
%"TAP"
"6","(-1975,4200)","2","mstr_standard","I169";
;
CDS_LIB"mstr_standard"
BODY_TYPE"PLUMBING"
HDL_TAP"TRUE";
"B \NAC \NWC"1;
"S \NAC"
BN"13"168;
%"TAP"
"6","(-1975,4100)","2","mstr_standard","I170";
;
CDS_LIB"mstr_standard"
BODY_TYPE"PLUMBING"
HDL_TAP"TRUE";
"B \NAC \NWC"1;
"S \NAC"
BN"12"166;
%"TAP"
"6","(-1975,4400)","2","mstr_standard","I171";
;
CDS_LIB"mstr_standard"
BODY_TYPE"PLUMBING"
HDL_TAP"TRUE";
"B \NAC \NWC"1;
"S \NAC"
BN"15"172;
%"TAP"
"6","(-1975,4500)","2","mstr_standard","I172";
;
CDS_LIB"mstr_standard"
BODY_TYPE"PLUMBING"
HDL_TAP"TRUE";
"B \NAC \NWC"1;
"S \NAC"
BN"16"174;
%"TAP"
"6","(-1775,4150)","2","mstr_standard","I173";
;
CDS_LIB"mstr_standard"
BODY_TYPE"PLUMBING"
HDL_TAP"TRUE";
"B \NAC \NWC"2;
"S \NAC"
BN"13"167;
%"TAP"
"6","(-1775,4250)","2","mstr_standard","I174";
;
CDS_LIB"mstr_standard"
BODY_TYPE"PLUMBING"
HDL_TAP"TRUE";
"B \NAC \NWC"2;
"S \NAC"
BN"14"169;
%"TAP"
"6","(-1775,4350)","2","mstr_standard","I175";
;
CDS_LIB"mstr_standard"
BODY_TYPE"PLUMBING"
HDL_TAP"TRUE";
"B \NAC \NWC"2;
"S \NAC"
BN"15"171;
%"TAP"
"6","(-1775,4450)","2","mstr_standard","I176";
;
CDS_LIB"mstr_standard"
BODY_TYPE"PLUMBING"
HDL_TAP"TRUE";
"B \NAC \NWC"2;
"S \NAC"
BN"16"173;
%"TAP"
"6","(-1775,4550)","2","mstr_standard","I177";
;
CDS_LIB"mstr_standard"
BODY_TYPE"PLUMBING"
HDL_TAP"TRUE";
"B \NAC \NWC"2;
"S \NAC"
BN"17"175;
%"TAP"
"6","(-1975,4600)","2","mstr_standard","I178";
;
CDS_LIB"mstr_standard"
BODY_TYPE"PLUMBING"
HDL_TAP"TRUE";
"B \NAC \NWC"1;
"S \NAC"
BN"17"176;
%"P12V_NVDIMM_GHJ"
"1","(-2375,2425)","0","mstr_symbols","I181";
;
VOLTAGE"12.0"
CDS_LIB"mstr_symbols"
BODY_TYPE"PLUMBING"
HDL_POWER"P12V_NVDIMM_GHJ";
"G\NAC"16;
%"SCONN288_H44441003"
"1","(-5225,2700)","0","mstr_sconn","I24";
;
CDS_SEC"1"
PART_NUMBER"H44441-003"
MATERIAL"SCONN"
LOCATION"J9U1"
BOM_SS"NOPOP"
PACK_TYPE"PIP"
BOM_COST"MEM"
CDS_LIB"mstr_sconn"
SEC_TYPE"PIP"
SEC"1"
CDS_LOCATION"J9U1"
ROOM"DDR4_GH_H";
"DQ<63>"
$PN"280"27;
"BA<1>"
$PN"224"83;
"CK1N"
$PN"219"90;
"CK0P"
$PN"74"76;
"S3_N_C<1>"
$PN"237"77;
"S2_N_C<0>"
$PN"93"78;
"S1_N"
$PN"89"79;
"DQ<29>"
$PN"181"101;
"DQ<28>"
$PN"36"102;
"C<2>"
$PN"235"75;
"A0"
$PN"79"84;
"A1"
$PN"72"85;
"A12"
$PN"65"138;
"A13"
$PN"232"139;
"A17"
$PN"234"140;
"A3"
$PN"71"91;
"A4"
$PN"214"92;
"A5"
$PN"213"93;
"A6"
$PN"69"94;
"A7"
$PN"211"95;
"A8"
$PN"68"96;
"A9"
$PN"66"97;
"CB<6>"
$PN"54"66;
"CB<5>"
$PN"192"67;
"CB<4>"
$PN"47"68;
"CB<3>"
$PN"201"69;
"CB<2>"
$PN"56"70;
"CB<1>"
$PN"194"45;
"CB<0>"
$PN"49"46;
"CK0N"
$PN"75"82;
"CKE<1>"
$PN"203"80;
"DQ<62>"
$PN"135"147;
"DQ<61>"
$PN"273"144;
"DQ<60>"
$PN"128"145;
"DQ<59>"
$PN"282"32;
"DQ<56>"
$PN"130"122;
"DQ<55>"
$PN"269"123;
"DQ<46>"
$PN"113"28;
"DQ<45>"
$PN"251"124;
"DQ<44>"
$PN"106"125;
"DQ<43>"
$PN"260"126;
"DQ<42>"
$PN"115"127;
"DQ<41>"
$PN"253"128;
"DQ<40>"
$PN"108"129;
"DQ<39>"
$PN"247"130;
"DQ<37>"
$PN"240"103;
"DQ<34>"
$PN"104"104;
"DQ<33>"
$PN"242"105;
"DQ<32>"
$PN"97"106;
"DQ<31>"
$PN"188"107;
"DQ<30>"
$PN"43"108;
"DQ<25>"
$PN"183"119;
"DQ<24>"
$PN"38"109;
"DQ<23>"
$PN"177"118;
"DQ<22>"
$PN"32"110;
"DQ<21>"
$PN"170"111;
"DQ<20>"
$PN"25"112;
"DQ<19>"
$PN"179"121;
"DQ<18>"
$PN"34"113;
"DQ<16>"
$PN"27"47;
"DQ<14>"
$PN"21"61;
"DQ<13>"
$PN"159"48;
"DQ<12>"
$PN"14"63;
"DQ<11>"
$PN"168"49;
"DQ<10>"
$PN"23"50;
"DQ<9>"
$PN"161"60;
"DQ<8>"
$PN"16"51;
"DQ<7>"
$PN"155"59;
"DQ<6>"
$PN"10"52;
"EVENT_N"
$PN"78"35;
"PAR"
$PN"222"64;
"RESET_N"
$PN"58"65;
"RFU<2>"
$PN"144"37;
"SCL"
$PN"141"42;
"SDA"
$PN"285"43;
"VREFCA"
$PN"146"36;
"CK1P"
$PN"218"89;
"BG<0>"
$PN"63"86;
"BG<1>"
$PN"207"87;
"BA<0>"
$PN"81"88;
"SA<0>"
$PN"139"20;
"VDDSPD"
$PN"284"20;
"SA<2>"
$PN"238"13;
"SA<1>"
$PN"140"20;
"DQ<1>"
$PN"150"53;
"DQ<0>"
$PN"5"54;
"ACT_N"
$PN"62"40;
"ALERT_N"
$PN"208"44;
"A2"
$PN"216"98;
"DQ<35>"
$PN"249"114;
"DQ<36>"
$PN"95"115;
"DQ<38>"
$PN"102"131;
"A10"
$PN"225"99;
"A11"
$PN"210"100;
"A14_WE_N"
$PN"228"141;
"A15_CAS_N"
$PN"86"142;
"A16_RAS_N"
$PN"82"143;
"CB<7>"
$PN"199"71;
"ODT<0>"
$PN"87"72;
"ODT<1>"
$PN"91"73;
"CKE<0>"
$PN"60"74;
"S0_N"
$PN"84"81;
"DQ<27>"
$PN"190"116;
"DQ<26>"
$PN"45"120;
"DQ<15>"
$PN"166"55;
"DQ<17>"
$PN"172"117;
"RFU<0>"
$PN"205"38;
"RFU<1>"
$PN"227"39;
"SAVE_N_NC"
$PN"230"41;
"DQ<57>"
$PN"275"24;
"DQ<58>"
$PN"137"146;
"DQ<54>"
$PN"124"132;
"DQ<53>"
$PN"262"33;
"DQ<52>"
$PN"117"34;
"DQ<51>"
$PN"271"133;
"DQ<50>"
$PN"126"137;
"DQ<49>"
$PN"264"134;
"DQ<48>"
$PN"119"135;
"DQ<47>"
$PN"258"136;
"DQ<2>"
$PN"12"57;
"DQ<3>"
$PN"157"58;
"DQ<4>"
$PN"3"56;
"DQ<5>"
$PN"148"62;
%"TAP"
"6","(-5975,1950)","0","mstr_standard","I25";
;
CDS_LIB"mstr_standard"
BODY_TYPE"PLUMBING"
HDL_TAP"TRUE";
"B \NAC \NWC"12;
"S \NAC"
BN"0"46;
%"TAP"
"6","(-5975,2000)","0","mstr_standard","I26";
;
CDS_LIB"mstr_standard"
BODY_TYPE"PLUMBING"
HDL_TAP"TRUE";
"B \NAC \NWC"12;
"S \NAC"
BN"1"45;
%"TAP"
"6","(-5975,2100)","0","mstr_standard","I27";
;
CDS_LIB"mstr_standard"
BODY_TYPE"PLUMBING"
HDL_TAP"TRUE";
"B \NAC \NWC"12;
"S \NAC"
BN"3"69;
%"TAP"
"6","(-5975,2050)","0","mstr_standard","I28";
;
CDS_LIB"mstr_standard"
BODY_TYPE"PLUMBING"
HDL_TAP"TRUE";
"B \NAC \NWC"12;
"S \NAC"
BN"2"70;
%"TAP"
"6","(-5975,2200)","0","mstr_standard","I29";
;
CDS_LIB"mstr_standard"
BODY_TYPE"PLUMBING"
HDL_TAP"TRUE";
"B \NAC \NWC"12;
"S \NAC"
BN"5"67;
%"CAP_A"
"1","(-7225,1000)","2","dev_discrete","I3";
;
LOCATION"C1G10"
PART_NUMBER"A36096-045"
VALUE"0.01UF"
TOLERANCE"10%"
PACK_TYPE"0402V"
VOLTAGE"25V"
MATERIAL"X7R"
CDS_LOCATION"C1G10"
BOM_COST"MEM"
CDS_LIB"dev_discrete"
CDS_SEC"1"
$SEC"1"
ROOM"DDR4_GH_G";
"B"
$PN"2"17;
"A"
$PN"1"36;
%"TAP"
"6","(-5975,2150)","0","mstr_standard","I30";
;
CDS_LIB"mstr_standard"
BODY_TYPE"PLUMBING"
HDL_TAP"TRUE";
"B \NAC \NWC"12;
"S \NAC"
BN"4"68;
%"TAP"
"6","(-5975,2250)","0","mstr_standard","I31";
;
CDS_LIB"mstr_standard"
BODY_TYPE"PLUMBING"
HDL_TAP"TRUE";
"B \NAC \NWC"12;
"S \NAC"
BN"6"66;
%"TAP"
"6","(-5975,2300)","0","mstr_standard","I32";
;
CDS_LIB"mstr_standard"
BODY_TYPE"PLUMBING"
HDL_TAP"TRUE";
"B \NAC \NWC"12;
"S \NAC"
BN"7"71;
%"TAP"
"6","(-5975,2400)","0","mstr_standard","I33";
;
CDS_LIB"mstr_standard"
BODY_TYPE"PLUMBING"
HDL_TAP"TRUE";
"B \NAC \NWC"11;
"S \NAC"
BN"2"72;
%"TAP"
"6","(-5975,2450)","0","mstr_standard","I34";
;
CDS_LIB"mstr_standard"
BODY_TYPE"PLUMBING"
HDL_TAP"TRUE";
"B \NAC \NWC"11;
"S \NAC"
BN"3"73;
%"TAP"
"6","(-6175,3000)","0","mstr_standard","I35";
;
CDS_LIB"mstr_standard"
BODY_TYPE"PLUMBING"
HDL_TAP"TRUE";
"B \NAC \NWC"5;
"S \NAC"
BN"2"82;
%"TAP"
"6","(-6175,3100)","0","mstr_standard","I36";
;
CDS_LIB"mstr_standard"
BODY_TYPE"PLUMBING"
HDL_TAP"TRUE";
"B \NAC \NWC"5;
"S \NAC"
BN"3"90;
%"TAP"
"6","(-5975,2600)","0","mstr_standard","I37";
;
CDS_LIB"mstr_standard"
BODY_TYPE"PLUMBING"
HDL_TAP"TRUE";
"B \NAC \NWC"10;
"S \NAC"
BN"3"80;
%"TAP"
"6","(-5975,2550)","0","mstr_standard","I38";
;
CDS_LIB"mstr_standard"
BODY_TYPE"PLUMBING"
HDL_TAP"TRUE";
"B \NAC \NWC"10;
"S \NAC"
BN"2"74;
%"TAP"
"6","(-5975,2750)","0","mstr_standard","I39";
;
CDS_LIB"mstr_standard"
BODY_TYPE"PLUMBING"
HDL_TAP"TRUE";
"B \NAC \NWC"9;
"S \NAC"
BN"5"79;
%"GND"
"1","(-7225,750)","0","mstr_symbols","I4";
;
VOLTAGE"0"
BOM_COST"MEM"
SIZE"1B"
CDS_LIB"mstr_symbols"
BODY_TYPE"PLUMBING"
ROOM"DDR4_GH_G"
HDL_POWER"GND";
"A\NAC"17;
%"TAP"
"6","(-5975,2700)","0","mstr_standard","I40";
;
CDS_LIB"mstr_standard"
BODY_TYPE"PLUMBING"
HDL_TAP"TRUE";
"B \NAC \NWC"9;
"S \NAC"
BN"4"81;
%"TAP"
"6","(-5975,2850)","0","mstr_standard","I41";
;
CDS_LIB"mstr_standard"
BODY_TYPE"PLUMBING"
HDL_TAP"TRUE";
"B \NAC \NWC"9;
"S \NAC"
BN"7"77;
%"TAP"
"6","(-5975,2800)","0","mstr_standard","I42";
;
CDS_LIB"mstr_standard"
BODY_TYPE"PLUMBING"
HDL_TAP"TRUE";
"B \NAC \NWC"9;
"S \NAC"
BN"6"78;
%"TAP"
"6","(-5975,3150)","0","mstr_standard","I43";
;
CDS_LIB"mstr_standard"
BODY_TYPE"PLUMBING"
HDL_TAP"TRUE";
"B \NAC \NWC"6;
"S \NAC"
BN"3"89;
%"TAP"
"6","(-5975,3050)","0","mstr_standard","I44";
;
CDS_LIB"mstr_standard"
BODY_TYPE"PLUMBING"
HDL_TAP"TRUE";
"B \NAC \NWC"6;
"S \NAC"
BN"2"76;
%"TAP"
"6","(-5975,3250)","0","mstr_standard","I45";
;
CDS_LIB"mstr_standard"
BODY_TYPE"PLUMBING"
HDL_TAP"TRUE";
"B \NAC \NWC"8;
"S \NAC"
BN"0"86;
%"TAP"
"6","(-5975,3350)","0","mstr_standard","I46";
;
CDS_LIB"mstr_standard"
BODY_TYPE"PLUMBING"
HDL_TAP"TRUE";
"B \NAC \NWC"7;
"S \NAC"
BN"0"88;
%"TAP"
"6","(-5975,3300)","0","mstr_standard","I47";
;
CDS_LIB"mstr_standard"
BODY_TYPE"PLUMBING"
HDL_TAP"TRUE";
"B \NAC \NWC"8;
"S \NAC"
BN"1"87;
%"TAP"
"6","(-5975,3400)","0","mstr_standard","I48";
;
CDS_LIB"mstr_standard"
BODY_TYPE"PLUMBING"
HDL_TAP"TRUE";
"B \NAC \NWC"7;
"S \NAC"
BN"1"83;
%"TAP"
"6","(-5975,3500)","0","mstr_standard","I49";
;
CDS_LIB"mstr_standard"
BODY_TYPE"PLUMBING"
HDL_TAP"TRUE";
"B \NAC \NWC"4;
"S \NAC"
BN"0"84;
%"TAP"
"6","(-4475,1200)","2","mstr_standard","I50";
;
CDS_LIB"mstr_standard"
BODY_TYPE"PLUMBING"
HDL_TAP"TRUE";
"B \NAC \NWC"3;
"S \NAC"
BN"0"54;
%"TAP"
"6","(-4475,1350)","2","mstr_standard","I51";
;
CDS_LIB"mstr_standard"
BODY_TYPE"PLUMBING"
HDL_TAP"TRUE";
"B \NAC \NWC"3;
"S \NAC"
BN"3"58;
%"TAP"
"6","(-4475,1250)","2","mstr_standard","I52";
;
CDS_LIB"mstr_standard"
BODY_TYPE"PLUMBING"
HDL_TAP"TRUE";
"B \NAC \NWC"3;
"S \NAC"
BN"1"53;
%"TAP"
"6","(-4475,1300)","2","mstr_standard","I53";
;
CDS_LIB"mstr_standard"
BODY_TYPE"PLUMBING"
HDL_TAP"TRUE";
"B \NAC \NWC"3;
"S \NAC"
BN"2"57;
%"TAP"
"6","(-4475,1450)","2","mstr_standard","I54";
;
CDS_LIB"mstr_standard"
BODY_TYPE"PLUMBING"
HDL_TAP"TRUE";
"B \NAC \NWC"3;
"S \NAC"
BN"5"62;
%"TAP"
"6","(-4475,1400)","2","mstr_standard","I55";
;
CDS_LIB"mstr_standard"
BODY_TYPE"PLUMBING"
HDL_TAP"TRUE";
"B \NAC \NWC"3;
"S \NAC"
BN"4"56;
%"SCONN288_H44441003"
"4","(-3075,1450)","0","mstr_sconn","I56";
;
CDS_SEC"4"
LOCATION"J9U1"
PART_NUMBER"H44441-003"
MATERIAL"SCONN"
BOM_SS"NOPOP"
PACK_TYPE"PIP"
BOM_COST"MEM"
CDS_LIB"mstr_sconn"
SEC_TYPE"PIP"
SEC"4"
CDS_LOCATION"J9U1"
ROOM"DDR4_GH_H";
"VDD<0>"
$PN"236"18;
"VDD<6>"
$PN"220"18;
"VDD<10>"
$PN"209"18;
"VDD<13>"
$PN"92"18;
"VDD<16>"
$PN"85"18;
"VDD<19>"
$PN"76"18;
"VDD<23>"
$PN"64"18;
"VDD<25>"
$PN"59"18;
"VTT<0>"
$PN"221"19;
"12V<1>"
$PN"1"16;
"12V<0>"
$PN"145"16;
"VDD<24>"
$PN"61"18;
"VDD<22>"
$PN"67"18;
"VDD<21>"
$PN"70"18;
"VDD<20>"
$PN"73"18;
"VDD<18>"
$PN"80"18;
"VDD<17>"
$PN"83"18;
"VDD<15>"
$PN"88"18;
"VDD<14>"
$PN"90"18;
"VDD<12>"
$PN"204"18;
"VDD<11>"
$PN"206"18;
"VDD<9>"
$PN"212"18;
"VDD<8>"
$PN"215"18;
"VDD<7>"
$PN"217"18;
"VDD<5>"
$PN"223"18;
"VDD<4>"
$PN"226"18;
"VDD<3>"
$PN"229"18;
"VDD<2>"
$PN"231"18;
"VDD<1>"
$PN"233"18;
"VPP<4>"
$PN"142"21;
"VPP<3>"
$PN"143"21;
"VPP<2>"
$PN"288"21;
"VPP<1>"
$PN"286"21;
"VPP<0>"
$PN"287"21;
"VTT<1>"
$PN"77"19;
%"TAP"
"6","(-4475,1550)","2","mstr_standard","I57";
;
CDS_LIB"mstr_standard"
BODY_TYPE"PLUMBING"
HDL_TAP"TRUE";
"B \NAC \NWC"3;
"S \NAC"
BN"7"59;
%"TAP"
"6","(-4475,1500)","2","mstr_standard","I58";
;
CDS_LIB"mstr_standard"
BODY_TYPE"PLUMBING"
HDL_TAP"TRUE";
"B \NAC \NWC"3;
"S \NAC"
BN"6"52;
%"TAP"
"6","(-4475,1600)","2","mstr_standard","I59";
;
CDS_LIB"mstr_standard"
BODY_TYPE"PLUMBING"
HDL_TAP"TRUE";
"B \NAC \NWC"3;
"S \NAC"
BN"8"51;
%"TAP"
"6","(-4475,1650)","2","mstr_standard","I60";
;
CDS_LIB"mstr_standard"
BODY_TYPE"PLUMBING"
HDL_TAP"TRUE";
"B \NAC \NWC"3;
"S \NAC"
BN"9"60;
%"TAP"
"6","(-4475,1700)","2","mstr_standard","I61";
;
CDS_LIB"mstr_standard"
BODY_TYPE"PLUMBING"
HDL_TAP"TRUE";
"B \NAC \NWC"3;
"S \NAC"
BN"10"50;
%"TAP"
"6","(-4475,1750)","2","mstr_standard","I62";
;
CDS_LIB"mstr_standard"
BODY_TYPE"PLUMBING"
HDL_TAP"TRUE";
"B \NAC \NWC"3;
"S \NAC"
BN"11"49;
%"TAP"
"6","(-4475,1850)","2","mstr_standard","I63";
;
CDS_LIB"mstr_standard"
BODY_TYPE"PLUMBING"
HDL_TAP"TRUE";
"B \NAC \NWC"3;
"S \NAC"
BN"13"48;
%"TAP"
"6","(-4475,1800)","2","mstr_standard","I64";
;
CDS_LIB"mstr_standard"
BODY_TYPE"PLUMBING"
HDL_TAP"TRUE";
"B \NAC \NWC"3;
"S \NAC"
BN"12"63;
%"TAP"
"6","(-4475,2000)","2","mstr_standard","I65";
;
CDS_LIB"mstr_standard"
BODY_TYPE"PLUMBING"
HDL_TAP"TRUE";
"B \NAC \NWC"3;
"S \NAC"
BN"16"47;
%"TAP"
"6","(-4475,1900)","2","mstr_standard","I66";
;
CDS_LIB"mstr_standard"
BODY_TYPE"PLUMBING"
HDL_TAP"TRUE";
"B \NAC \NWC"3;
"S \NAC"
BN"14"61;
%"TAP"
"6","(-4475,1950)","2","mstr_standard","I67";
;
CDS_LIB"mstr_standard"
BODY_TYPE"PLUMBING"
HDL_TAP"TRUE";
"B \NAC \NWC"3;
"S \NAC"
BN"15"55;
%"TAP"
"6","(-4475,2050)","2","mstr_standard","I68";
;
CDS_LIB"mstr_standard"
BODY_TYPE"PLUMBING"
HDL_TAP"TRUE";
"B \NAC \NWC"3;
"S \NAC"
BN"17"117;
%"TAP"
"6","(-4475,2100)","2","mstr_standard","I69";
;
CDS_LIB"mstr_standard"
BODY_TYPE"PLUMBING"
HDL_TAP"TRUE";
"B \NAC \NWC"3;
"S \NAC"
BN"18"113;
%"TAP"
"6","(-4475,2250)","2","mstr_standard","I70";
;
CDS_LIB"mstr_standard"
BODY_TYPE"PLUMBING"
HDL_TAP"TRUE";
"B \NAC \NWC"3;
"S \NAC"
BN"21"111;
%"TAP"
"6","(-4475,2150)","2","mstr_standard","I71";
;
CDS_LIB"mstr_standard"
BODY_TYPE"PLUMBING"
HDL_TAP"TRUE";
"B \NAC \NWC"3;
"S \NAC"
BN"19"121;
%"TAP"
"6","(-4475,2200)","2","mstr_standard","I72";
;
CDS_LIB"mstr_standard"
BODY_TYPE"PLUMBING"
HDL_TAP"TRUE";
"B \NAC \NWC"3;
"S \NAC"
BN"20"112;
%"TAP"
"6","(-4475,2300)","2","mstr_standard","I73";
;
CDS_LIB"mstr_standard"
BODY_TYPE"PLUMBING"
HDL_TAP"TRUE";
"B \NAC \NWC"3;
"S \NAC"
BN"22"110;
%"TAP"
"6","(-4475,2350)","2","mstr_standard","I74";
;
CDS_LIB"mstr_standard"
BODY_TYPE"PLUMBING"
HDL_TAP"TRUE";
"B \NAC \NWC"3;
"S \NAC"
BN"23"118;
%"TAP"
"6","(-4475,2500)","2","mstr_standard","I75";
;
CDS_LIB"mstr_standard"
BODY_TYPE"PLUMBING"
HDL_TAP"TRUE";
"B \NAC \NWC"3;
"S \NAC"
BN"26"120;
%"TAP"
"6","(-4475,2450)","2","mstr_standard","I76";
;
CDS_LIB"mstr_standard"
BODY_TYPE"PLUMBING"
HDL_TAP"TRUE";
"B \NAC \NWC"3;
"S \NAC"
BN"25"119;
%"TAP"
"6","(-4475,2400)","2","mstr_standard","I77";
;
CDS_LIB"mstr_standard"
BODY_TYPE"PLUMBING"
HDL_TAP"TRUE";
"B \NAC \NWC"3;
"S \NAC"
BN"24"109;
%"PVDDQ_GHJ"
"1","(-4175,1975)","0","mstr_symbols","I78";
;
VOLTAGE"1.2V"
BOM_COST"MEM"
CDS_LIB"mstr_symbols"
BODY_TYPE"PLUMBING"
ROOM"DDR4_GH_G"
HDL_POWER"PVDDQ_GHJ";
"G\NAC"18;
%"PVTT_GHJ"
"1","(-3925,2150)","0","mstr_symbols","I79";
;
VOLTAGE"0.6V"
BOM_COST"MEM"
CDS_LIB"mstr_symbols"
BODY_TYPE"PLUMBING"
ROOM"DDR4_GH_G"
HDL_POWER"PVTT_GHJ";
"G\NAC"19;
%"PVPP_GHJ"
"1","(-7825,1700)","0","mstr_symbols","I8";
;
VOLTAGE"2.5V"
BOM_COST"MEM"
CDS_LIB"mstr_symbols"
BODY_TYPE"PLUMBING"
ROOM"DDR4_GH_G"
HDL_POWER"PVPP_GHJ";
"G\NAC"20;
%"PVPP_GHJ"
"1","(-3775,2450)","0","mstr_symbols","I80";
;
VOLTAGE"2.5V"
BOM_COST"MEM"
CDS_LIB"mstr_symbols"
BODY_TYPE"PLUMBING"
ROOM"DDR4_GH_G"
HDL_POWER"PVPP_GHJ";
"G\NAC"21;
%"TAP"
"6","(-4475,2550)","2","mstr_standard","I81";
;
CDS_LIB"mstr_standard"
BODY_TYPE"PLUMBING"
HDL_TAP"TRUE";
"B \NAC \NWC"3;
"S \NAC"
BN"27"116;
%"TAP"
"6","(-4475,2600)","2","mstr_standard","I82";
;
CDS_LIB"mstr_standard"
BODY_TYPE"PLUMBING"
HDL_TAP"TRUE";
"B \NAC \NWC"3;
"S \NAC"
BN"28"102;
%"TAP"
"6","(-4475,2650)","2","mstr_standard","I83";
;
CDS_LIB"mstr_standard"
BODY_TYPE"PLUMBING"
HDL_TAP"TRUE";
"B \NAC \NWC"3;
"S \NAC"
BN"29"101;
%"TAP"
"6","(-4475,2750)","2","mstr_standard","I84";
;
CDS_LIB"mstr_standard"
BODY_TYPE"PLUMBING"
HDL_TAP"TRUE";
"B \NAC \NWC"3;
"S \NAC"
BN"31"107;
%"TAP"
"6","(-4475,2700)","2","mstr_standard","I85";
;
CDS_LIB"mstr_standard"
BODY_TYPE"PLUMBING"
HDL_TAP"TRUE";
"B \NAC \NWC"3;
"S \NAC"
BN"30"108;
%"TAP"
"6","(-4475,2850)","2","mstr_standard","I86";
;
CDS_LIB"mstr_standard"
BODY_TYPE"PLUMBING"
HDL_TAP"TRUE";
"B \NAC \NWC"3;
"S \NAC"
BN"33"105;
%"TAP"
"6","(-4475,2800)","2","mstr_standard","I87";
;
CDS_LIB"mstr_standard"
BODY_TYPE"PLUMBING"
HDL_TAP"TRUE";
"B \NAC \NWC"3;
"S \NAC"
BN"32"106;
%"TAP"
"6","(-4475,2900)","2","mstr_standard","I88";
;
CDS_LIB"mstr_standard"
BODY_TYPE"PLUMBING"
HDL_TAP"TRUE";
"B \NAC \NWC"3;
"S \NAC"
BN"34"104;
%"TAP"
"6","(-4475,3000)","2","mstr_standard","I89";
;
CDS_LIB"mstr_standard"
BODY_TYPE"PLUMBING"
HDL_TAP"TRUE";
"B \NAC \NWC"3;
"S \NAC"
BN"36"115;
%"TAP"
"6","(-4475,2950)","2","mstr_standard","I90";
;
CDS_LIB"mstr_standard"
BODY_TYPE"PLUMBING"
HDL_TAP"TRUE";
"B \NAC \NWC"3;
"S \NAC"
BN"35"114;
%"TAP"
"6","(-4475,3100)","2","mstr_standard","I91";
;
CDS_LIB"mstr_standard"
BODY_TYPE"PLUMBING"
HDL_TAP"TRUE";
"B \NAC \NWC"3;
"S \NAC"
BN"38"131;
%"TAP"
"6","(-4475,3050)","2","mstr_standard","I92";
;
CDS_LIB"mstr_standard"
BODY_TYPE"PLUMBING"
HDL_TAP"TRUE";
"B \NAC \NWC"3;
"S \NAC"
BN"37"103;
%"TAP"
"6","(-4475,3150)","2","mstr_standard","I93";
;
CDS_LIB"mstr_standard"
BODY_TYPE"PLUMBING"
HDL_TAP"TRUE";
"B \NAC \NWC"3;
"S \NAC"
BN"39"130;
%"TAP"
"6","(-4475,3250)","2","mstr_standard","I94";
;
CDS_LIB"mstr_standard"
BODY_TYPE"PLUMBING"
HDL_TAP"TRUE";
"B \NAC \NWC"3;
"S \NAC"
BN"41"128;
%"TAP"
"6","(-4475,3200)","2","mstr_standard","I95";
;
CDS_LIB"mstr_standard"
BODY_TYPE"PLUMBING"
HDL_TAP"TRUE";
"B \NAC \NWC"3;
"S \NAC"
BN"40"129;
%"TAP"
"6","(-4475,3350)","2","mstr_standard","I96";
;
CDS_LIB"mstr_standard"
BODY_TYPE"PLUMBING"
HDL_TAP"TRUE";
"B \NAC \NWC"3;
"S \NAC"
BN"43"126;
%"TAP"
"6","(-4475,3300)","2","mstr_standard","I97";
;
CDS_LIB"mstr_standard"
BODY_TYPE"PLUMBING"
HDL_TAP"TRUE";
"B \NAC \NWC"3;
"S \NAC"
BN"42"127;
%"TAP"
"6","(-4475,3400)","2","mstr_standard","I98";
;
CDS_LIB"mstr_standard"
BODY_TYPE"PLUMBING"
HDL_TAP"TRUE";
"B \NAC \NWC"3;
"S \NAC"
BN"44"125;
%"TAP"
"6","(-4475,3500)","2","mstr_standard","I99";
;
CDS_LIB"mstr_standard"
BODY_TYPE"PLUMBING"
HDL_TAP"TRUE";
"B \NAC \NWC"3;
"S \NAC"
BN"46"28;
END.
